# S9S_MB_2U (Grand Teton) — schematic netlist excerpt (pin names and nets, part order shuffled) for the footprints in the layout excerpt that follows; sources: Cadence DE-HDL packaged netlist, KiCad conversion of 03242023_DA0F0TMBIJ0_F0T_Motherboard_J_brd_V01_OCP.brd

C365  Q_CAP  47UF 4V 20% X6S  pkg C0805  page 75 : A = PVCCIN_CPU0 ; B = GND
R179  Q_RES  100 1% CHIP  pkg 0402LF  page 124 : A = PWRGD_DRAMPWRGD_CPU0_EF_LVC1_R2 ; B = PVCCD_HV_CPU0
R985  Q_RES  33.2 1% CHIP  pkg 0402LF  page 222 : A = FM_PVCCIN_CPU1_R_EN ; B = FM_PVCCIN_CPU1_EN

(kicad_pcb
	(version 20260206)
	(generator "pcbnew")
	(generator_version "10.0")
	(general
		(thickness 1.6)
		(legacy_teardrops no)
	)
	(paper "A4")
	(title_block
		(title "03242023_DA0F0TMBIJ0_F0T_Motherboard_J_brd_V01_OCP.brd")
		(comment 1 "Grand Teton / footprints 5530-5532 of 6105")
	)
	(layers
		(0 "F.Cu" signal "TOP")
		(4 "In1.Cu" signal "GND")
		(6 "In2.Cu" signal "IN1")
		(8 "In3.Cu" signal "GND1")
		(10 "In4.Cu" signal "IN2")
		(12 "In5.Cu" signal "GND2")
		(14 "In6.Cu" signal "IN3")
		(16 "In7.Cu" signal "GND3")
		(18 "In8.Cu" signal "VCC")
		(20 "In9.Cu" signal "VCC1")
		(22 "In10.Cu" signal "GND4")
		(24 "In11.Cu" signal "IN4")
		(26 "In12.Cu" signal "GND5")
		(28 "In13.Cu" signal "IN5")
		(30 "In14.Cu" signal "GND6")
		(32 "In15.Cu" signal "IN6")
		(34 "In16.Cu" signal "GND7")
		(2 "B.Cu" signal "BOTTOM")
		(9 "F.Adhes" user "F.Adhesive")
		(11 "B.Adhes" user "B.Adhesive")
		(13 "F.Paste" user "Package Geometry/Pastemask Top")
		(15 "B.Paste" user "Package Geometry/Pastemask Bottom")
		(5 "F.SilkS" user "Ref Des/Silkscreen Top")
		(7 "B.SilkS" user "Ref Des/Silkscreen Bottom")
		(1 "F.Mask" user "Board Geometry/Soldermask Top")
		(3 "B.Mask" user "Board Geometry/Soldermask Bottom")
		(17 "Dwgs.User" user "User.Drawings")
		(19 "Cmts.User" user "User.Comments")
		(21 "Eco1.User" user "User.Eco1")
		(23 "Eco2.User" user "User.Eco2")
		(25 "Edge.Cuts" user "Board Geometry/Outline")
		(27 "Margin" user)
		(31 "F.CrtYd" user "Package Geometry/Place Bound Top")
		(29 "B.CrtYd" user "Package Geometry/Place Bound Bottom")
		(35 "F.Fab" user "Ref Des/Assembly Top")
		(33 "B.Fab" user "Ref Des/Assembly Bottom")
	)
	(footprint ""
		(layer "B.Cu")
		(at 399.670778 -190.77559 90)
		(property "Reference" "R179"
			(at 0 0 90)
			(layer "B.SilkS")
			(hide yes)
			(effects
				(font
					(size 1.27 1.27)
				)
				(justify mirror)
			)
		)
		(property "Value" ""
			(at 0 0 90)
			(layer "B.Fab")
			(effects
				(font
					(size 1.27 1.27)
				)
				(justify mirror)
			)
		)
		(duplicate_pad_numbers_are_jumpers no)
		(fp_line
			(start 0.7874 -0.4064)
			(end -0.7874 -0.4064)
			(stroke
				(width 0.1524)
				(type default)
			)
			(layer "B.SilkS")
		)
		(fp_line
			(start -0.7874 -0.4064)
			(end -0.7874 0.4064)
			(stroke
				(width 0.1524)
				(type default)
			)
			(layer "B.SilkS")
		)
		(fp_line
			(start 0.7874 0.4064)
			(end 0.7874 -0.4064)
			(stroke
				(width 0.1524)
				(type default)
			)
			(layer "B.SilkS")
		)
		(fp_line
			(start -0.7874 0.4064)
			(end 0.7874 0.4064)
			(stroke
				(width 0.1524)
				(type default)
			)
			(layer "B.SilkS")
		)
		(fp_line
			(start 0.67945 -0.305054)
			(end 0.12065 -0.305054)
			(stroke
				(width 0.1)
				(type default)
			)
			(layer "B.Fab")
		)
		(fp_line
			(start 0.12065 -0.305054)
			(end 0.12065 -0.2794)
			(stroke
				(width 0.1)
				(type default)
			)
			(layer "B.Fab")
		)
		(fp_line
			(start -0.12065 -0.3048)
			(end -0.67945 -0.3048)
			(stroke
				(width 0.1)
				(type default)
			)
			(layer "B.Fab")
		)
		(fp_line
			(start -0.67945 -0.3048)
			(end -0.67945 0.3048)
			(stroke
				(width 0.1)
				(type default)
			)
			(layer "B.Fab")
		)
		(fp_line
			(start 0.12065 -0.2794)
			(end -0.12065 -0.2794)
			(stroke
				(width 0.1)
				(type default)
			)
			(layer "B.Fab")
		)
		(fp_line
			(start -0.12065 -0.2794)
			(end -0.12065 -0.3048)
			(stroke
				(width 0.1)
				(type default)
			)
			(layer "B.Fab")
		)
		(fp_line
			(start 0.12065 0.2794)
			(end 0.12065 0.3048)
			(stroke
				(width 0.1)
				(type default)
			)
			(layer "B.Fab")
		)
		(fp_line
			(start -0.120396 0.2794)
			(end 0.12065 0.2794)
			(stroke
				(width 0.1)
				(type default)
			)
			(layer "B.Fab")
		)
		(fp_line
			(start 0.67945 0.3048)
			(end 0.67945 -0.305054)
			(stroke
				(width 0.1)
				(type default)
			)
			(layer "B.Fab")
		)
		(fp_line
			(start 0.12065 0.3048)
			(end 0.67945 0.3048)
			(stroke
				(width 0.1)
				(type default)
			)
			(layer "B.Fab")
		)
		(fp_line
			(start -0.120396 0.3048)
			(end -0.120396 0.2794)
			(stroke
				(width 0.1)
				(type default)
			)
			(layer "B.Fab")
		)
		(fp_line
			(start -0.67945 0.3048)
			(end -0.120396 0.3048)
			(stroke
				(width 0.1)
				(type default)
			)
			(layer "B.Fab")
		)
		(pad "1" smd circle
			(at 0.40005 0 270)
			(size 0 0)
			(layers "B.Cu" "B.Mask" "B.Paste")
			(net "PWRGD_DRAMPWRGD_CPU0_EF_LVC1_R2")
		)
		(pad "2" smd circle
			(at -0.40005 0 270)
			(size 0 0)
			(layers "B.Cu" "B.Mask" "B.Paste")
			(net "PVCCD_HV_CPU0")
		)
	)
	(footprint ""
		(layer "B.Cu")
		(at 160.83788 -120.106948)
		(property "Reference" "R985"
			(at 0 0 0)
			(layer "B.SilkS")
			(hide yes)
			(effects
				(font
					(size 1.27 1.27)
				)
				(justify mirror)
			)
		)
		(property "Value" ""
			(at 0 0 0)
			(layer "B.Fab")
			(effects
				(font
					(size 1.27 1.27)
				)
				(justify mirror)
			)
		)
		(duplicate_pad_numbers_are_jumpers no)
		(fp_line
			(start -0.7874 -0.4064)
			(end -0.7874 0.4064)
			(stroke
				(width 0.1524)
				(type default)
			)
			(layer "B.SilkS")
		)
		(fp_line
			(start -0.7874 0.4064)
			(end 0.7874 0.4064)
			(stroke
				(width 0.1524)
				(type default)
			)
			(layer "B.SilkS")
		)
		(fp_line
			(start 0.7874 -0.4064)
			(end -0.7874 -0.4064)
			(stroke
				(width 0.1524)
				(type default)
			)
			(layer "B.SilkS")
		)
		(fp_line
			(start 0.7874 0.4064)
			(end 0.7874 -0.4064)
			(stroke
				(width 0.1524)
				(type default)
			)
			(layer "B.SilkS")
		)
		(fp_line
			(start -0.67945 -0.3048)
			(end -0.67945 0.3048)
			(stroke
				(width 0.1)
				(type default)
			)
			(layer "B.Fab")
		)
		(fp_line
			(start -0.67945 0.3048)
			(end -0.120396 0.3048)
			(stroke
				(width 0.1)
				(type default)
			)
			(layer "B.Fab")
		)
		(fp_line
			(start -0.12065 -0.3048)
			(end -0.67945 -0.3048)
			(stroke
				(width 0.1)
				(type default)
			)
			(layer "B.Fab")
		)
		(fp_line
			(start -0.12065 -0.2794)
			(end -0.12065 -0.3048)
			(stroke
				(width 0.1)
				(type default)
			)
			(layer "B.Fab")
		)
		(fp_line
			(start -0.120396 0.2794)
			(end 0.12065 0.2794)
			(stroke
				(width 0.1)
				(type default)
			)
			(layer "B.Fab")
		)
		(fp_line
			(start -0.120396 0.3048)
			(end -0.120396 0.2794)
			(stroke
				(width 0.1)
				(type default)
			)
			(layer "B.Fab")
		)
		(fp_line
			(start 0.12065 -0.305054)
			(end 0.12065 -0.2794)
			(stroke
				(width 0.1)
				(type default)
			)
			(layer "B.Fab")
		)
		(fp_line
			(start 0.12065 -0.2794)
			(end -0.12065 -0.2794)
			(stroke
				(width 0.1)
				(type default)
			)
			(layer "B.Fab")
		)
		(fp_line
			(start 0.12065 0.2794)
			(end 0.12065 0.3048)
			(stroke
				(width 0.1)
				(type default)
			)
			(layer "B.Fab")
		)
		(fp_line
			(start 0.12065 0.3048)
			(end 0.67945 0.3048)
			(stroke
				(width 0.1)
				(type default)
			)
			(layer "B.Fab")
		)
		(fp_line
			(start 0.67945 -0.305054)
			(end 0.12065 -0.305054)
			(stroke
				(width 0.1)
				(type default)
			)
			(layer "B.Fab")
		)
		(fp_line
			(start 0.67945 0.3048)
			(end 0.67945 -0.305054)
			(stroke
				(width 0.1)
				(type default)
			)
			(layer "B.Fab")
		)
		(pad "1" smd circle
			(at 0.40005 0 180)
			(size 0 0)
			(layers "B.Cu" "B.Mask" "B.Paste")
			(net "FM_PVCCIN_CPU1_R_EN")
		)
		(pad "2" smd circle
			(at -0.40005 0 180)
			(size 0 0)
			(layers "B.Cu" "B.Mask" "B.Paste")
			(net "FM_PVCCIN_CPU1_EN")
		)
	)
	(footprint ""
		(layer "B.Cu")
		(at 351.841308 -252.176026 -90)
		(property "Reference" "C365"
			(at 0 0 90)
			(layer "B.SilkS")
			(hide yes)
			(effects
				(font
					(size 1.27 1.27)
				)
				(justify mirror)
			)
		)
		(property "Value" ""
			(at 0 0 90)
			(layer "B.Fab")
			(effects
				(font
					(size 1.27 1.27)
				)
				(justify mirror)
			)
		)
		(duplicate_pad_numbers_are_jumpers no)
		(fp_line
			(start -1.524 0.762)
			(end 1.524 0.762)
			(stroke
				(width 0.1524)
				(type default)
			)
			(layer "B.SilkS")
		)
		(fp_line
			(start 1.524 0.762)
			(end 1.524 -0.762)
			(stroke
				(width 0.1524)
				(type default)
			)
			(layer "B.SilkS")
		)
		(fp_line
			(start -1.524 -0.762)
			(end -1.524 0.762)
			(stroke
				(width 0.1524)
				(type default)
			)
			(layer "B.SilkS")
		)
		(fp_line
			(start 1.524 -0.762)
			(end -1.524 -0.762)
			(stroke
				(width 0.1524)
				(type default)
			)
			(layer "B.SilkS")
		)
		(fp_line
			(start -1.1049 0.724916)
			(end -1.1049 -0.724916)
			(stroke
				(width 0.1)
				(type default)
			)
			(layer "B.Fab")
		)
		(fp_line
			(start 1.1049 0.724916)
			(end -1.1049 0.724916)
			(stroke
				(width 0.1)
				(type default)
			)
			(layer "B.Fab")
		)
		(fp_line
			(start -1.1049 -0.724916)
			(end 1.1049 -0.724916)
			(stroke
				(width 0.1)
				(type default)
			)
			(layer "B.Fab")
		)
		(fp_line
			(start 1.1049 -0.724916)
			(end 1.1049 0.724916)
			(stroke
				(width 0.1)
				(type default)
			)
			(layer "B.Fab")
		)
		(pad "1" smd rect
			(at 0.889 0 270)
			(size 1.016 1.27)
			(layers "B.Cu" "B.Mask" "B.Paste")
			(net "PVCCIN_CPU0")
		)
		(pad "2" smd rect
			(at -0.889 0 270)
			(size 1.016 1.27)
			(layers "B.Cu" "B.Mask" "B.Paste")
			(net "GND")
		)
	)
)
